# T6G (Grand Teton) — schematic netlist excerpt (pin names and nets, part order shuffled) for the footprints in the layout excerpt that follows; sources: Cadence DE-HDL packaged netlist, KiCad conversion of 04192023_DAF0TMB3IC0_F0TG_MB_C_brd_V02_OCP.brd

R1338  Q_RES  4.7K 5% CHIP  pkg 0402LF  page 84 : A = P3V3_AUX ; B = SCM_IRQ_N
C8020  Q_CAP  100NF 50V 10% EMPTY  pkg C0402  page 268 : A = UV_P2V5_COMP ; B = GND

(kicad_pcb
	(version 20260206)
	(generator "pcbnew")
	(generator_version "10.0")
	(general
		(thickness 1.6)
		(legacy_teardrops no)
	)
	(paper "A4")
	(title_block
		(title "04192023_DAF0TMB3IC0_F0TG_MB_C_brd_V02_OCP.brd")
		(comment 1 "Grand Teton / footprints 3514-3516 of 8354")
	)
	(layers
		(0 "F.Cu" signal "TOP")
		(4 "In1.Cu" signal "GND")
		(6 "In2.Cu" signal "IN1")
		(8 "In3.Cu" signal "GND1")
		(10 "In4.Cu" signal "IN2")
		(12 "In5.Cu" signal "GND2")
		(14 "In6.Cu" signal "IN3")
		(16 "In7.Cu" signal "GND3")
		(18 "In8.Cu" signal "VCC")
		(20 "In9.Cu" signal "VCC1")
		(22 "In10.Cu" signal "GND4")
		(24 "In11.Cu" signal "IN4")
		(26 "In12.Cu" signal "GND5")
		(28 "In13.Cu" signal "IN5")
		(30 "In14.Cu" signal "GND6")
		(32 "In15.Cu" signal "IN6")
		(34 "In16.Cu" signal "GND7")
		(2 "B.Cu" signal "BOTTOM")
		(9 "F.Adhes" user "F.Adhesive")
		(11 "B.Adhes" user "B.Adhesive")
		(13 "F.Paste" user "Package Geometry/Pastemask Top")
		(15 "B.Paste" user "Package Geometry/Pastemask Bottom")
		(5 "F.SilkS" user "Ref Des/Silkscreen Top")
		(7 "B.SilkS" user "Ref Des/Silkscreen Bottom")
		(1 "F.Mask" user "Board Geometry/Soldermask Top")
		(3 "B.Mask" user "Board Geometry/Soldermask Bottom")
		(17 "Dwgs.User" user "User.Drawings")
		(19 "Cmts.User" user "User.Comments")
		(21 "Eco1.User" user "User.Eco1")
		(23 "Eco2.User" user "User.Eco2")
		(25 "Edge.Cuts" user "Board Geometry/Outline")
		(27 "Margin" user)
		(31 "F.CrtYd" user "Package Geometry/Place Bound Top")
		(29 "B.CrtYd" user "Package Geometry/Place Bound Bottom")
		(35 "F.Fab" user "Ref Des/Assembly Top")
		(33 "B.Fab" user "Ref Des/Assembly Bottom")
	)
	(footprint ""
		(layer "F.Cu")
		(at 142.748 -114.554)
		(property "Reference" "C8020"
			(at 0 0 0)
			(layer "F.SilkS")
			(hide yes)
			(effects
				(font
					(size 1.27 1.27)
				)
			)
		)
		(property "Value" ""
			(at 0 0 0)
			(layer "F.Fab")
			(effects
				(font
					(size 1.27 1.27)
				)
			)
		)
		(duplicate_pad_numbers_are_jumpers no)
		(fp_line
			(start -0.7874 -0.4064)
			(end 0.7874 -0.4064)
			(stroke
				(width 0.1524)
				(type default)
			)
			(layer "F.SilkS")
		)
		(fp_line
			(start -0.7874 0.4064)
			(end -0.7874 -0.4064)
			(stroke
				(width 0.1524)
				(type default)
			)
			(layer "F.SilkS")
		)
		(fp_line
			(start 0.7874 -0.4064)
			(end 0.7874 0.4064)
			(stroke
				(width 0.1524)
				(type default)
			)
			(layer "F.SilkS")
		)
		(fp_line
			(start 0.7874 0.4064)
			(end -0.7874 0.4064)
			(stroke
				(width 0.1524)
				(type default)
			)
			(layer "F.SilkS")
		)
		(fp_line
			(start -0.67945 -0.305054)
			(end -0.12065 -0.305054)
			(stroke
				(width 0.1)
				(type default)
			)
			(layer "F.Fab")
		)
		(fp_line
			(start -0.67945 0.3048)
			(end -0.67945 -0.305054)
			(stroke
				(width 0.1)
				(type default)
			)
			(layer "F.Fab")
		)
		(fp_line
			(start -0.12065 -0.305054)
			(end -0.12065 -0.2794)
			(stroke
				(width 0.1)
				(type default)
			)
			(layer "F.Fab")
		)
		(fp_line
			(start -0.12065 -0.2794)
			(end 0.12065 -0.2794)
			(stroke
				(width 0.1)
				(type default)
			)
			(layer "F.Fab")
		)
		(fp_line
			(start -0.12065 0.2794)
			(end -0.12065 0.3048)
			(stroke
				(width 0.1)
				(type default)
			)
			(layer "F.Fab")
		)
		(fp_line
			(start -0.12065 0.3048)
			(end -0.67945 0.3048)
			(stroke
				(width 0.1)
				(type default)
			)
			(layer "F.Fab")
		)
		(fp_line
			(start 0.120396 0.2794)
			(end -0.12065 0.2794)
			(stroke
				(width 0.1)
				(type default)
			)
			(layer "F.Fab")
		)
		(fp_line
			(start 0.120396 0.3048)
			(end 0.120396 0.2794)
			(stroke
				(width 0.1)
				(type default)
			)
			(layer "F.Fab")
		)
		(fp_line
			(start 0.12065 -0.3048)
			(end 0.67945 -0.3048)
			(stroke
				(width 0.1)
				(type default)
			)
			(layer "F.Fab")
		)
		(fp_line
			(start 0.12065 -0.2794)
			(end 0.12065 -0.3048)
			(stroke
				(width 0.1)
				(type default)
			)
			(layer "F.Fab")
		)
		(fp_line
			(start 0.67945 -0.3048)
			(end 0.67945 0.3048)
			(stroke
				(width 0.1)
				(type default)
			)
			(layer "F.Fab")
		)
		(fp_line
			(start 0.67945 0.3048)
			(end 0.120396 0.3048)
			(stroke
				(width 0.1)
				(type default)
			)
			(layer "F.Fab")
		)
		(pad "1" smd circle
			(at -0.40005 0)
			(size 0 0)
			(layers "F.Cu" "F.Mask" "F.Paste")
			(net "UV_P2V5_COMP")
		)
		(pad "2" smd circle
			(at 0.40005 0)
			(size 0 0)
			(layers "F.Cu" "F.Mask" "F.Paste")
			(net "GND")
		)
	)
	(footprint ""
		(layer "F.Cu")
		(at 151.13 -114.173 180)
		(property "Reference" "R1338"
			(at 0 0 180)
			(layer "F.SilkS")
			(hide yes)
			(effects
				(font
					(size 1.27 1.27)
				)
			)
		)
		(property "Value" ""
			(at 0 0 180)
			(layer "F.Fab")
			(effects
				(font
					(size 1.27 1.27)
				)
			)
		)
		(duplicate_pad_numbers_are_jumpers no)
		(fp_line
			(start 0.7874 0.4064)
			(end -0.7874 0.4064)
			(stroke
				(width 0.1524)
				(type default)
			)
			(layer "F.SilkS")
		)
		(fp_line
			(start 0.7874 -0.4064)
			(end 0.7874 0.4064)
			(stroke
				(width 0.1524)
				(type default)
			)
			(layer "F.SilkS")
		)
		(fp_line
			(start -0.7874 0.4064)
			(end -0.7874 -0.4064)
			(stroke
				(width 0.1524)
				(type default)
			)
			(layer "F.SilkS")
		)
		(fp_line
			(start -0.7874 -0.4064)
			(end 0.7874 -0.4064)
			(stroke
				(width 0.1524)
				(type default)
			)
			(layer "F.SilkS")
		)
		(fp_line
			(start 0.67945 0.3048)
			(end 0.120396 0.3048)
			(stroke
				(width 0.1)
				(type default)
			)
			(layer "F.Fab")
		)
		(fp_line
			(start 0.67945 -0.3048)
			(end 0.67945 0.3048)
			(stroke
				(width 0.1)
				(type default)
			)
			(layer "F.Fab")
		)
		(fp_line
			(start 0.12065 -0.2794)
			(end 0.12065 -0.3048)
			(stroke
				(width 0.1)
				(type default)
			)
			(layer "F.Fab")
		)
		(fp_line
			(start 0.12065 -0.3048)
			(end 0.67945 -0.3048)
			(stroke
				(width 0.1)
				(type default)
			)
			(layer "F.Fab")
		)
		(fp_line
			(start 0.120396 0.3048)
			(end 0.120396 0.2794)
			(stroke
				(width 0.1)
				(type default)
			)
			(layer "F.Fab")
		)
		(fp_line
			(start 0.120396 0.2794)
			(end -0.12065 0.2794)
			(stroke
				(width 0.1)
				(type default)
			)
			(layer "F.Fab")
		)
		(fp_line
			(start -0.12065 0.3048)
			(end -0.67945 0.3048)
			(stroke
				(width 0.1)
				(type default)
			)
			(layer "F.Fab")
		)
		(fp_line
			(start -0.12065 0.2794)
			(end -0.12065 0.3048)
			(stroke
				(width 0.1)
				(type default)
			)
			(layer "F.Fab")
		)
		(fp_line
			(start -0.12065 -0.2794)
			(end 0.12065 -0.2794)
			(stroke
				(width 0.1)
				(type default)
			)
			(layer "F.Fab")
		)
		(fp_line
			(start -0.12065 -0.305054)
			(end -0.12065 -0.2794)
			(stroke
				(width 0.1)
				(type default)
			)
			(layer "F.Fab")
		)
		(fp_line
			(start -0.67945 0.3048)
			(end -0.67945 -0.305054)
			(stroke
				(width 0.1)
				(type default)
			)
			(layer "F.Fab")
		)
		(fp_line
			(start -0.67945 -0.305054)
			(end -0.12065 -0.305054)
			(stroke
				(width 0.1)
				(type default)
			)
			(layer "F.Fab")
		)
		(pad "1" smd circle
			(at -0.40005 0 180)
			(size 0 0)
			(layers "F.Cu" "F.Mask" "F.Paste")
			(net "P3V3_AUX")
		)
		(pad "2" smd circle
			(at 0.40005 0 180)
			(size 0 0)
			(layers "F.Cu" "F.Mask" "F.Paste")
			(net "SCM_IRQ_N")
		)
	)
	(footprint ""
		(layer "F.Cu")
		(at 69.098668 -382.951228)
		(property "Reference" "ME10"
			(at 0 0 0)
			(layer "F.SilkS")
			(hide yes)
			(effects
				(font
					(size 1.27 1.27)
				)
			)
		)
		(property "Value" ""
			(at 0 0 0)
			(layer "F.Fab")
			(effects
				(font
					(size 1.27 1.27)
				)
			)
		)
		(duplicate_pad_numbers_are_jumpers no)
	)
)
